# BASEBOARD_FAB2 (Tioga Pass) — schematic netlist excerpt (pin names and nets, part order shuffled) for the footprints in the layout excerpt that follows; sources: Cadence DE-HDL packaged netlist, KiCad conversion of Wiwynn_Tioga_Pass_MB.brd

C7U1  CAP_A  47UF 4V 20% X5R  pkg 0603V  page 225 : A = PVDDQ_GHJ ; B = GND
R782  RES  0.0 5% CHIP  pkg 0402  page 244 : A = P3E_CPU0_PE1_PCH_RXN<9> ; B = P3E_CPU0_PE1_PCH_CON_RXN<9>
C4P2  CAP  100UF 4V 20% X5R  pkg 0805  page 42 : A = PVCCMCP_CPU0 ; B = GND

(kicad_pcb
	(version 20260206)
	(generator "pcbnew")
	(generator_version "10.0")
	(general
		(thickness 1.6)
		(legacy_teardrops no)
	)
	(paper "A4")
	(title_block
		(title "Wiwynn_Tioga_Pass_MB.brd")
		(comment 1 "Tioga Pass / footprints 4657-4659 of 4770")
	)
	(layers
		(0 "F.Cu" signal "TOP")
		(4 "In1.Cu" signal "L2GND")
		(6 "In2.Cu" signal "L3")
		(8 "In3.Cu" signal "L4GND")
		(10 "In4.Cu" signal "L5")
		(12 "In5.Cu" signal "L6GND")
		(14 "In6.Cu" signal "L7VCC")
		(16 "In7.Cu" signal "L8VCC")
		(18 "In8.Cu" signal "L9GND")
		(20 "In9.Cu" signal "L10")
		(22 "In10.Cu" signal "L11GND")
		(24 "In11.Cu" signal "L12")
		(26 "In12.Cu" signal "L13GND")
		(2 "B.Cu" signal "BOTTOM")
		(9 "F.Adhes" user "F.Adhesive")
		(11 "B.Adhes" user "B.Adhesive")
		(13 "F.Paste" user "Package Geometry/Pastemask Top")
		(15 "B.Paste" user "Package Geometry/Pastemask Bottom")
		(5 "F.SilkS" user "Ref Des/Silkscreen Top")
		(7 "B.SilkS" user "Ref Des/Silkscreen Bottom")
		(1 "F.Mask" user "Board Geometry/Soldermask Top")
		(3 "B.Mask" user "Board Geometry/Soldermask Bottom")
		(17 "Dwgs.User" user "User.Drawings")
		(19 "Cmts.User" user "User.Comments")
		(21 "Eco1.User" user "User.Eco1")
		(23 "Eco2.User" user "User.Eco2")
		(25 "Edge.Cuts" user "Board Geometry/Outline")
		(27 "Margin" user)
		(31 "F.CrtYd" user "Package Geometry/Place Bound Top")
		(29 "B.CrtYd" user "Package Geometry/Place Bound Bottom")
		(35 "F.Fab" user "Ref Des/Assembly Top")
		(33 "B.Fab" user "Ref Des/Assembly Bottom")
	)
	(footprint ""
		(layer "B.Cu")
		(at 111.000032 -8.1534 90)
		(property "Reference" "C7U1"
			(at -1.848866 0.752348 90)
			(unlocked yes)
			(layer "B.SilkS")
			(effects
				(font
					(size 1.27 0.9652)
					(thickness 0.1524)
				)
				(justify mirror)
			)
		)
		(property "Value" ""
			(at 0 0 90)
			(layer "B.Fab")
			(effects
				(font
					(size 1.27 1.27)
				)
				(justify mirror)
			)
		)
		(duplicate_pad_numbers_are_jumpers no)
		(fp_rect
			(start 0.500126 1.598422)
			(end -0.500126 -0.201422)
			(stroke
				(width 0)
				(type default)
			)
			(fill no)
			(layer "B.CrtYd")
		)
		(fp_line
			(start 0.500126 -0.201422)
			(end -0.500126 -0.201422)
			(stroke
				(width 0.1)
				(type default)
			)
			(layer "B.Fab")
		)
		(fp_line
			(start -0.500126 -0.201422)
			(end -0.500126 1.598422)
			(stroke
				(width 0.1)
				(type default)
			)
			(layer "B.Fab")
		)
		(fp_line
			(start 0.500126 1.598422)
			(end 0.500126 -0.201422)
			(stroke
				(width 0.1)
				(type default)
			)
			(layer "B.Fab")
		)
		(fp_line
			(start -0.500126 1.598422)
			(end 0.500126 1.598422)
			(stroke
				(width 0.1)
				(type default)
			)
			(layer "B.Fab")
		)
		(pad "1" smd rect
			(at 0 0)
			(size 0.889 0.9906)
			(layers "B.Cu" "B.Mask" "B.Paste")
			(net "PVDDQ_GHJ")
		)
		(pad "2" smd rect
			(at 0 1.397)
			(size 0.889 0.9906)
			(layers "B.Cu" "B.Mask" "B.Paste")
			(net "GND")
		)
		(zone
			(layer "B.Cu")
			(hatch none 0.5)
			(connect_pads
				(clearance 0)
			)
			(min_thickness 0.25)
			(keepout
				(tracks not_allowed)
				(vias allowed)
				(pads allowed)
				(copperpour not_allowed)
				(footprints allowed)
			)
			(placement
				(enabled no)
				(sheetname "")
			)
			(fill
				(thermal_gap 0.5)
				(thermal_bridge_width 0.5)
				(island_removal_mode 0)
			)
			(polygon
				(pts
					(xy 111.952532 -8.6487) (xy 111.444532 -8.6487) (xy 111.444532 -7.6581) (xy 111.952532 -7.6581)
				)
			)
		)
		(zone
			(layer "B.Cu")
			(hatch none 0.5)
			(connect_pads
				(clearance 0)
			)
			(min_thickness 0.25)
			(keepout
				(tracks allowed)
				(vias not_allowed)
				(pads allowed)
				(copperpour not_allowed)
				(footprints allowed)
			)
			(placement
				(enabled no)
				(sheetname "")
			)
			(fill
				(thermal_gap 0.5)
				(thermal_bridge_width 0.5)
				(island_removal_mode 0)
			)
			(polygon
				(pts
					(xy 111.952532 -8.6487) (xy 111.444532 -8.6487) (xy 111.444532 -7.6581) (xy 111.952532 -7.6581)
				)
			)
		)
	)
	(footprint ""
		(layer "B.Cu")
		(at 367.827814 -125.507242 -90)
		(property "Reference" "R782"
			(at 0.8382 -0.67818 270)
			(unlocked yes)
			(layer "B.SilkS")
			(effects
				(font
					(size 0.4064 0.254)
					(thickness 0.1524)
				)
				(justify left mirror)
			)
		)
		(property "Value" ""
			(at 0 0 90)
			(layer "B.Fab")
			(effects
				(font
					(size 1.27 1.27)
				)
				(justify mirror)
			)
		)
		(duplicate_pad_numbers_are_jumpers no)
		(fp_poly
			(pts
				(xy 0.2794 -0.1016) (xy -0.2794 -0.1016) (xy -0.2794 0.9906) (xy 0.2794 0.9906)
			)
			(stroke
				(width 0)
				(type default)
			)
			(fill no)
			(layer "B.CrtYd")
		)
		(fp_line
			(start -0.2794 0.9906)
			(end -0.2794 -0.1016)
			(stroke
				(width 0.1)
				(type default)
			)
			(layer "B.Fab")
		)
		(fp_line
			(start 0.2794 0.9906)
			(end -0.2794 0.9906)
			(stroke
				(width 0.1)
				(type default)
			)
			(layer "B.Fab")
		)
		(fp_line
			(start -0.2794 -0.1016)
			(end 0.2794 -0.1016)
			(stroke
				(width 0.1)
				(type default)
			)
			(layer "B.Fab")
		)
		(fp_line
			(start 0.2794 -0.1016)
			(end 0.2794 0.9906)
			(stroke
				(width 0.1)
				(type default)
			)
			(layer "B.Fab")
		)
		(pad "1" smd rect
			(at 0 0 90)
			(size 0.508 0.508)
			(layers "B.Cu" "B.Mask" "B.Paste")
			(net "P3E_CPU0_PE1_PCH_RXN<9>")
		)
		(pad "2" smd rect
			(at 0 0.889 90)
			(size 0.508 0.508)
			(layers "B.Cu" "B.Mask" "B.Paste")
			(net "P3E_CPU0_PE1_PCH_CON_RXN<9>")
		)
		(zone
			(layer "B.Cu")
			(hatch none 0.5)
			(connect_pads
				(clearance 0)
			)
			(min_thickness 0.25)
			(keepout
				(tracks not_allowed)
				(vias allowed)
				(pads allowed)
				(copperpour not_allowed)
				(footprints allowed)
			)
			(placement
				(enabled no)
				(sheetname "")
			)
			(fill
				(thermal_gap 0.5)
				(thermal_bridge_width 0.5)
				(island_removal_mode 0)
			)
			(polygon
				(pts
					(xy 367.192814 -125.253242) (xy 367.192814 -125.761242) (xy 367.573814 -125.761242) (xy 367.573814 -125.253242)
				)
			)
		)
		(zone
			(layer "B.Cu")
			(hatch none 0.5)
			(connect_pads
				(clearance 0)
			)
			(min_thickness 0.25)
			(keepout
				(tracks allowed)
				(vias not_allowed)
				(pads allowed)
				(copperpour not_allowed)
				(footprints allowed)
			)
			(placement
				(enabled no)
				(sheetname "")
			)
			(fill
				(thermal_gap 0.5)
				(thermal_bridge_width 0.5)
				(island_removal_mode 0)
			)
			(polygon
				(pts
					(xy 367.573814 -125.253242) (xy 367.573814 -125.761242) (xy 367.192814 -125.761242) (xy 367.192814 -125.253242)
				)
			)
		)
	)
	(footprint ""
		(layer "B.Cu")
		(at 279.046686 -79.60614 180)
		(property "Reference" "C4P2"
			(at 0 0 0)
			(layer "B.SilkS")
			(hide yes)
			(effects
				(font
					(size 1.27 1.27)
				)
				(justify mirror)
			)
		)
		(property "Value" ""
			(at 0 0 0)
			(layer "B.Fab")
			(effects
				(font
					(size 1.27 1.27)
				)
				(justify mirror)
			)
		)
		(duplicate_pad_numbers_are_jumpers no)
		(fp_poly
			(pts
				(xy 0.7239 -0.2159) (xy -0.7239 -0.2159) (xy -0.7239 1.9939) (xy 0.7239 1.9939)
			)
			(stroke
				(width 0)
				(type default)
			)
			(fill no)
			(layer "B.CrtYd")
		)
		(fp_line
			(start 0.7239 1.9939)
			(end -0.7239 1.9939)
			(stroke
				(width 0.1)
				(type default)
			)
			(layer "B.Fab")
		)
		(fp_line
			(start 0.7239 -0.2159)
			(end 0.7239 1.9939)
			(stroke
				(width 0.1)
				(type default)
			)
			(layer "B.Fab")
		)
		(fp_line
			(start -0.7239 1.9939)
			(end -0.7239 -0.2159)
			(stroke
				(width 0.1)
				(type default)
			)
			(layer "B.Fab")
		)
		(fp_line
			(start -0.7239 -0.2159)
			(end 0.7239 -0.2159)
			(stroke
				(width 0.1)
				(type default)
			)
			(layer "B.Fab")
		)
		(pad "1" smd rect
			(at 0 0)
			(size 1.27 1.016)
			(layers "B.Cu" "B.Mask" "B.Paste")
			(net "PVCCMCP_CPU0")
		)
		(pad "2" smd rect
			(at 0 1.778)
			(size 1.27 1.016)
			(layers "B.Cu" "B.Mask" "B.Paste")
			(net "GND")
		)
		(zone
			(layer "B.Cu")
			(hatch none 0.5)
			(connect_pads
				(clearance 0)
			)
			(min_thickness 0.25)
			(keepout
				(tracks not_allowed)
				(vias allowed)
				(pads allowed)
				(copperpour not_allowed)
				(footprints allowed)
			)
			(placement
				(enabled no)
				(sheetname "")
			)
			(fill
				(thermal_gap 0.5)
				(thermal_bridge_width 0.5)
				(island_removal_mode 0)
			)
			(polygon
				(pts
					(xy 278.411686 -80.11414) (xy 279.681686 -80.11414) (xy 279.681686 -80.87614) (xy 278.411686 -80.87614)
				)
			)
		)
	)
)
